(kicad_pcb
	(version 20240108)
	(generator "pcbnew")
	(generator_version "8.0")
	(general
		(thickness 1.6)
		(legacy_teardrops no)
	)
	(paper "A4")
	(title_block
		(title "Jetson Orin Baseboard OCuLink Expansion")
		(date "2025-03-18")
		(rev "1.1.0")
		(company "Antmicro Ltd")
		(comment 1 "www.antmicro.com")
		(comment 9 "footprints 13-13 of 119")
	)
	(layers
		(0 "F.Cu" signal)
		(1 "In1.Cu" signal)
		(2 "In2.Cu" signal)
		(31 "B.Cu" signal)
		(32 "B.Adhes" user "B.Adhesive")
		(33 "F.Adhes" user "F.Adhesive")
		(34 "B.Paste" user)
		(35 "F.Paste" user)
		(36 "B.SilkS" user "B.Silkscreen")
		(37 "F.SilkS" user "F.Silkscreen")
		(38 "B.Mask" user)
		(39 "F.Mask" user)
		(40 "Dwgs.User" user "User.Drawings")
		(41 "Cmts.User" user "User.Comments")
		(42 "Eco1.User" user "User.Eco1")
		(43 "Eco2.User" user "User.Eco2")
		(44 "Edge.Cuts" user)
		(45 "Margin" user)
		(46 "B.CrtYd" user "B.Courtyard")
		(47 "F.CrtYd" user "F.Courtyard")
		(48 "B.Fab" user)
		(49 "F.Fab" user)
	)
	(footprint "antmicro-footprints:WQFN-42-1EP_3.5x9mm_P0.5mm"
		(layer "F.Cu")
		(at 121.275 126.854 -90)
		(descr "WQFN, 42 Pin (http://www.ti.com/lit/ds/symlink/ts3l501e.pdf#page=23), generated with kicad-footprint-generator ipc_noLead_generator.py")
		(tags "WQFN NoLead")
		(property "Reference" "U3"
			(at -3.824 4.995 90)
			(layer "F.SilkS")
			(effects
				(font
					(size 0.7 0.7)
					(thickness 0.15)
				)
				(justify right top)
			)
		)
		(property "Value" "PI3EQX16904GL"
			(at 0 5.82 90)
			(layer "F.Fab")
			(effects
				(font
					(size 0.7 0.7)
					(thickness 0.15)
				)
				(justify right top)
			)
		)
		(property "Footprint" "antmicro-footprints:WQFN-42-1EP_3.5x9mm_P0.5mm"
			(at 0 0 90)
			(layer "F.Fab")
			(hide yes)
			(effects
				(font
					(size 1.27 1.27)
					(thickness 0.15)
				)
			)
		)
		(property "Datasheet" "https://www.diodes.com/part/view/PI3EQX16904GL"
			(at 0 0 90)
			(layer "F.Fab")
			(hide yes)
			(effects
				(font
					(size 1.27 1.27)
					(thickness 0.15)
				)
			)
		)
		(property "Description" "16Gbps 4-Channel ReDriver with Linear Equalization"
			(at 0 0 90)
			(layer "F.Fab")
			(hide yes)
			(effects
				(font
					(size 1.27 1.27)
					(thickness 0.15)
				)
			)
		)
		(property "MPN" "PI3EQX16904GLZHEX"
			(at 0 0 -90)
			(unlocked yes)
			(layer "F.Fab")
			(hide yes)
			(effects
				(font
					(size 1 1)
					(thickness 0.15)
				)
			)
		)
		(property "Manufacturer" "Diodes Incorporated"
			(at 0 0 -90)
			(unlocked yes)
			(layer "F.Fab")
			(hide yes)
			(effects
				(font
					(size 1 1)
					(thickness 0.15)
				)
			)
		)
		(property "Author" "Antmicro"
			(at 0 0 -90)
			(unlocked yes)
			(layer "F.Fab")
			(hide yes)
			(effects
				(font
					(size 1 1)
					(thickness 0.15)
				)
			)
		)
		(property "License" "Apache-2.0"
			(at 0 0 -90)
			(unlocked yes)
			(layer "F.Fab")
			(hide yes)
			(effects
				(font
					(size 1 1)
					(thickness 0.15)
				)
			)
		)
		(sheetname "Root")
		(sheetfile "jetson-orin-baseboard-oculink-expansion.kicad_sch")
		(attr smd)
		(fp_line
			(start -1.861 4.61)
			(end -1.861 4.384)
			(stroke
				(width 0.15)
				(type solid)
			)
			(layer "F.SilkS")
		)
		(fp_line
			(start -1.135 4.61)
			(end -1.861 4.61)
			(stroke
				(width 0.15)
				(type solid)
			)
			(layer "F.SilkS")
		)
		(fp_line
			(start 1.134 4.61)
			(end 1.86 4.61)
			(stroke
				(width 0.15)
				(type solid)
			)
			(layer "F.SilkS")
		)
		(fp_line
			(start 1.86 4.61)
			(end 1.86 4.384)
			(stroke
				(width 0.15)
				(type solid)
			)
			(layer "F.SilkS")
		)
		(fp_line
			(start -1.135 -4.611)
			(end -1.861 -4.611)
			(stroke
				(width 0.15)
				(type solid)
			)
			(layer "F.SilkS")
		)
		(fp_line
			(start 1.134 -4.611)
			(end 1.86 -4.611)
			(stroke
				(width 0.15)
				(type solid)
			)
			(layer "F.SilkS")
		)
		(fp_line
			(start 1.86 -4.611)
			(end 1.86 -4.385)
			(stroke
				(width 0.15)
				(type solid)
			)
			(layer "F.SilkS")
		)
		(fp_circle
			(center -2.68 -4)
			(end -2.63 -4)
			(stroke
				(width 0.15)
				(type solid)
			)
			(fill solid)
			(layer "F.SilkS")
		)
		(fp_rect
			(start -2.25 -5)
			(end 2.249 4.998)
			(stroke
				(width 0.05)
				(type solid)
			)
			(fill none)
			(layer "F.CrtYd")
		)
		(fp_line
			(start -1.75 4.498)
			(end -1.75 -3.625)
			(stroke
				(width 0.15)
				(type solid)
			)
			(layer "F.Fab")
		)
		(fp_line
			(start 1.749 4.498)
			(end -1.75 4.498)
			(stroke
				(width 0.15)
				(type solid)
			)
			(layer "F.Fab")
		)
		(fp_line
			(start -1.75 -3.625)
			(end -0.875 -4.5)
			(stroke
				(width 0.15)
				(type solid)
			)
			(layer "F.Fab")
		)
		(fp_line
			(start -0.875 -4.5)
			(end 1.749 -4.5)
			(stroke
				(width 0.15)
				(type solid)
			)
			(layer "F.Fab")
		)
		(fp_line
			(start 1.749 -4.5)
			(end 1.749 4.498)
			(stroke
				(width 0.15)
				(type solid)
			)
			(layer "F.Fab")
		)
		(fp_text user "License: Apache-2.0"
			(at -2.73 9.02 90)
			(layer "F.Fab")
			(hide yes)
			(effects
				(font
					(size 0.7 0.7)
					(thickness 0.15)
				)
				(justify right top)
			)
		)
		(fp_text user "${REFERENCE}"
			(at -2.73 10.22 90)
			(layer "F.Fab")
			(hide yes)
			(effects
				(font
					(size 0.7 0.7)
					(thickness 0.15)
				)
				(justify right top)
			)
		)
		(fp_text user "Author: Antmicro"
			(at -2.73 7.82 90)
			(layer "F.Fab")
			(hide yes)
			(effects
				(font
					(size 0.7 0.7)
					(thickness 0.15)
				)
				(justify right top)
			)
		)
		(pad "" smd roundrect
			(at -0.51 -3.242 270)
			(size 0.83 0.87)
			(layers "F.Paste")
			(roundrect_rratio 0.25)
		)
		(pad "" smd roundrect
			(at -0.51 -2.161 270)
			(size 0.83 0.87)
			(layers "F.Paste")
			(roundrect_rratio 0.25)
		)
		(pad "" smd roundrect
			(at -0.51 -1.081 270)
			(size 0.83 0.87)
			(layers "F.Paste")
			(roundrect_rratio 0.25)
		)
		(pad "" smd roundrect
			(at -0.51 0 270)
			(size 0.83 0.87)
			(layers "F.Paste")
			(roundrect_rratio 0.25)
		)
		(pad "" smd roundrect
			(at -0.51 1.08 270)
			(size 0.83 0.87)
			(layers "F.Paste")
			(roundrect_rratio 0.25)
		)
		(pad "" smd roundrect
			(at -0.51 2.16 270)
			(size 0.83 0.87)
			(layers "F.Paste")
			(roundrect_rratio 0.25)
		)
		(pad "" smd roundrect
			(at -0.51 3.24 270)
			(size 0.83 0.87)
			(layers "F.Paste")
			(roundrect_rratio 0.25)
		)
		(pad "" smd roundrect
			(at 0.508 -3.242 270)
			(size 0.83 0.87)
			(layers "F.Paste")
			(roundrect_rratio 0.25)
		)
		(pad "" smd roundrect
			(at 0.508 -2.161 270)
			(size 0.83 0.87)
			(layers "F.Paste")
			(roundrect_rratio 0.25)
		)
		(pad "" smd roundrect
			(at 0.508 -1.081 270)
			(size 0.83 0.87)
			(layers "F.Paste")
			(roundrect_rratio 0.25)
		)
		(pad "" smd roundrect
			(at 0.508 0 270)
			(size 0.83 0.87)
			(layers "F.Paste")
			(roundrect_rratio 0.25)
		)
		(pad "" smd roundrect
			(at 0.508 1.08 270)
			(size 0.83 0.87)
			(layers "F.Paste")
			(roundrect_rratio 0.25)
		)
		(pad "" smd roundrect
			(at 0.508 2.16 270)
			(size 0.83 0.87)
			(layers "F.Paste")
			(roundrect_rratio 0.25)
		)
		(pad "" smd roundrect
			(at 0.508 3.24 270)
			(size 0.83 0.87)
			(layers "F.Paste")
			(roundrect_rratio 0.25)
		)
		(pad "1" smd roundrect
			(at -1.688 -4 270)
			(size 0.875 0.25)
			(layers "F.Cu" "F.Paste" "F.Mask")
			(roundrect_rratio 0.25)
			(net 99 "/TX_EQ2")
			(pinfunction "EQ2")
			(pintype "passive")
		)
		(pad "2" smd roundrect
			(at -1.688 -3.5 270)
			(size 0.875 0.25)
			(layers "F.Cu" "F.Paste" "F.Mask")
			(roundrect_rratio 0.25)
			(net 102 "/TX_SW")
			(pinfunction "SW1")
			(pintype "input")
		)
		(pad "3" smd roundrect
			(at -1.688 -3 270)
			(size 0.875 0.25)
			(layers "F.Cu" "F.Paste" "F.Mask")
			(roundrect_rratio 0.25)
			(net 23 "+3V3")
			(pinfunction "VCC")
			(pintype "passive")
		)
		(pad "4" smd roundrect
			(at -1.688 -2.5 270)
			(size 0.875 0.25)
			(layers "F.Cu" "F.Paste" "F.Mask")
			(roundrect_rratio 0.25)
			(net 87 "/PCIE_{I}_TX1-")
			(pinfunction "A0RX+")
			(pintype "input")
		)
		(pad "5" smd roundrect
			(at -1.688 -2 270)
			(size 0.875 0.25)
			(layers "F.Cu" "F.Paste" "F.Mask")
			(roundrect_rratio 0.25)
			(net 86 "/PCIE_{I}_TX1+")
			(pinfunction "A0RX-")
			(pintype "input")
		)
		(pad "6" smd roundrect
			(at -1.688 -1.5 270)
			(size 0.875 0.25)
			(layers "F.Cu" "F.Paste" "F.Mask")
			(roundrect_rratio 0.25)
			(net 23 "+3V3")
			(pinfunction "VCC")
			(pintype "passive")
		)
		(pad "7" smd roundrect
			(at -1.688 -1 270)
			(size 0.875 0.25)
			(layers "F.Cu" "F.Paste" "F.Mask")
			(roundrect_rratio 0.25)
			(net 85 "/PCIE_{I}_TX0-")
			(pinfunction "A1RX+")
			(pintype "input")
		)
		(pad "8" smd roundrect
			(at -1.688 -0.5 270)
			(size 0.875 0.25)
			(layers "F.Cu" "F.Paste" "F.Mask")
			(roundrect_rratio 0.25)
			(net 88 "/PCIE_{I}_TX0+")
			(pinfunction "A1RX-")
			(pintype "input")
		)
		(pad "9" smd roundrect
			(at -1.688 0 270)
			(size 0.875 0.25)
			(layers "F.Cu" "F.Paste" "F.Mask")
			(roundrect_rratio 0.25)
			(net 23 "+3V3")
			(pinfunction "VCC")
			(pintype "passive")
		)
		(pad "10" smd roundrect
			(at -1.688 0.5 270)
			(size 0.875 0.25)
			(layers "F.Cu" "F.Paste" "F.Mask")
			(roundrect_rratio 0.25)
			(net 122 "unconnected-(U3-A2RX+-Pad10)")
			(pinfunction "A2RX+")
			(pintype "input+no_connect")
		)
		(pad "11" smd roundrect
			(at -1.688 1 270)
			(size 0.875 0.25)
			(layers "F.Cu" "F.Paste" "F.Mask")
			(roundrect_rratio 0.25)
			(net 124 "unconnected-(U3-A2RX--Pad11)")
			(pinfunction "A2RX-")
			(pintype "input+no_connect")
		)
		(pad "12" smd roundrect
			(at -1.688 1.5 270)
			(size 0.875 0.25)
			(layers "F.Cu" "F.Paste" "F.Mask")
			(roundrect_rratio 0.25)
			(net 23 "+3V3")
			(pinfunction "VCC")
			(pintype "power_in")
		)
		(pad "13" smd roundrect
			(at -1.688 2 270)
			(size 0.875 0.25)
			(layers "F.Cu" "F.Paste" "F.Mask")
			(roundrect_rratio 0.25)
			(net 131 "unconnected-(U3-A3RX+-Pad13)")
			(pinfunction "A3RX+")
			(pintype "input+no_connect")
		)
		(pad "14" smd roundrect
			(at -1.688 2.5 270)
			(size 0.875 0.25)
			(layers "F.Cu" "F.Paste" "F.Mask")
			(roundrect_rratio 0.25)
			(net 123 "unconnected-(U3-A3RX--Pad14)")
			(pinfunction "A3RX-")
			(pintype "input+no_connect")
		)
		(pad "15" smd roundrect
			(at -1.688 3 270)
			(size 0.875 0.25)
			(layers "F.Cu" "F.Paste" "F.Mask")
			(roundrect_rratio 0.25)
			(net 23 "+3V3")
			(pinfunction "VCC")
			(pintype "passive")
		)
		(pad "16" smd roundrect
			(at -1.688 3.5 270)
			(size 0.875 0.25)
			(layers "F.Cu" "F.Paste" "F.Mask")
			(roundrect_rratio 0.25)
			(net 112 "Net-(U3-~{I2C_{RESET}})")
			(pinfunction "~{I2C_{RESET}}")
			(pintype "input")
		)
		(pad "17" smd roundrect
			(at -1.688 4 270)
			(size 0.875 0.25)
			(layers "F.Cu" "F.Paste" "F.Mask")
			(roundrect_rratio 0.25)
			(net 130 "unconnected-(U3-AD1-Pad17)")
			(pinfunction "AD1")
			(pintype "passive+no_connect")
		)
		(pad "18" smd roundrect
			(at -0.75 4.437 270)
			(size 0.25 0.875)
			(layers "F.Cu" "F.Paste" "F.Mask")
			(roundrect_rratio 0.25)
			(net 107 "Net-(U3-SDA)")
			(pinfunction "SDA")
			(pintype "open_collector")
		)
		(pad "19" smd roundrect
			(at -0.25 4.437 270)
			(size 0.25 0.875)
			(layers "F.Cu" "F.Paste" "F.Mask")
			(roundrect_rratio 0.25)
			(net 108 "Net-(U3-SCL)")
			(pinfunction "SCL")
			(pintype "open_collector")
		)
		(pad "20" smd roundrect
			(at 0.25 4.437 270)
			(size 0.25 0.875)
			(layers "F.Cu" "F.Paste" "F.Mask")
			(roundrect_rratio 0.25)
			(net 71 "/~{CPRSNT}")
			(pinfunction "~{PRSNT}")
			(pintype "input")
		)
		(pad "21" smd roundrect
			(at 0.75 4.437 270)
			(size 0.25 0.875)
			(layers "F.Cu" "F.Paste" "F.Mask")
			(roundrect_rratio 0.25)
			(net 105 "Net-(U3-EN_{I2C})")
			(pinfunction "EN_{I2C}")
			(pintype "input")
		)
		(pad "22" smd roundrect
			(at 1.687 4 270)
			(size 0.875 0.25)
			(layers "F.Cu" "F.Paste" "F.Mask")
			(roundrect_rratio 0.25)
			(net 111 "Net-(U3-I2C_{DONE})")
			(pinfunction "I2C_{DONE}")
			(pintype "input")
		)
		(pad "23" smd roundrect
			(at 1.687 3.5 270)
			(size 0.875 0.25)
			(layers "F.Cu" "F.Paste" "F.Mask")
			(roundrect_rratio 0.25)
			(net 104 "Net-(U3-RXDET)")
			(pinfunction "RXDET")
			(pintype "input")
		)
		(pad "24" smd roundrect
			(at 1.687 3 270)
			(size 0.875 0.25)
			(layers "F.Cu" "F.Paste" "F.Mask")
			(roundrect_rratio 0.25)
			(net 23 "+3V3")
			(pinfunction "VCC")
			(pintype "passive")
		)
		(pad "25" smd roundrect
			(at 1.687 2.5 270)
			(size 0.875 0.25)
			(layers "F.Cu" "F.Paste" "F.Mask")
			(roundrect_rratio 0.25)
			(net 121 "unconnected-(U3-A3TX--Pad25)")
			(pinfunction "A3TX-")
			(pintype "output+no_connect")
		)
		(pad "26" smd roundrect
			(at 1.687 2 270)
			(size 0.875 0.25)
			(layers "F.Cu" "F.Paste" "F.Mask")
			(roundrect_rratio 0.25)
			(net 129 "unconnected-(U3-A3TX+-Pad26)")
			(pinfunction "A3TX+")
			(pintype "input+no_connect")
		)
		(pad "27" smd roundrect
			(at 1.687 1.5 270)
			(size 0.875 0.25)
			(layers "F.Cu" "F.Paste" "F.Mask")
			(roundrect_rratio 0.25)
			(net 23 "+3V3")
			(pinfunction "VCC")
			(pintype "passive")
		)
		(pad "28" smd roundrect
			(at 1.687 1 270)
			(size 0.875 0.25)
			(layers "F.Cu" "F.Paste" "F.Mask")
			(roundrect_rratio 0.25)
			(net 119 "unconnected-(U3-A2TX--Pad28)")
			(pinfunction "A2TX-")
			(pintype "output+no_connect")
		)
		(pad "29" smd roundrect
			(at 1.687 0.5 270)
			(size 0.875 0.25)
			(layers "F.Cu" "F.Paste" "F.Mask")
			(roundrect_rratio 0.25)
			(net 120 "unconnected-(U3-A2TX+-Pad29)")
			(pinfunction "A2TX+")
			(pintype "input+no_connect")
		)
		(pad "30" smd roundrect
			(at 1.687 0 270)
			(size 0.875 0.25)
			(layers "F.Cu" "F.Paste" "F.Mask")
			(roundrect_rratio 0.25)
			(net 23 "+3V3")
			(pinfunction "VCC")
			(pintype "passive")
		)
		(pad "31" smd roundrect
			(at 1.687 -0.5 270)
			(size 0.875 0.25)
			(layers "F.Cu" "F.Paste" "F.Mask")
			(roundrect_rratio 0.25)
			(net 63 "/PCIE_{O}_C.TX0+")
			(pinfunction "A1TX-")
			(pintype "output")
		)
		(pad "32" smd roundrect
			(at 1.687 -1 270)
			(size 0.875 0.25)
			(layers "F.Cu" "F.Paste" "F.Mask")
			(roundrect_rratio 0.25)
			(net 31 "/PCIE_{O}_C.TX0-")
			(pinfunction "A1TX+")
			(pintype "input")
		)
		(pad "33" smd roundrect
			(at 1.687 -1.5 270)
			(size 0.875 0.25)
			(layers "F.Cu" "F.Paste" "F.Mask")
			(roundrect_rratio 0.25)
			(net 23 "+3V3")
			(pinfunction "VCC")
			(pintype "passive")
		)
		(pad "34" smd roundrect
			(at 1.687 -2 270)
			(size 0.875 0.25)
			(layers "F.Cu" "F.Paste" "F.Mask")
			(roundrect_rratio 0.25)
			(net 57 "/PCIE_{O}_C.TX1+")
			(pinfunction "A0TX-")
			(pintype "output")
		)
		(pad "35" smd roundrect
			(at 1.687 -2.5 270)
			(size 0.875 0.25)
			(layers "F.Cu" "F.Paste" "F.Mask")
			(roundrect_rratio 0.25)
			(net 60 "/PCIE_{O}_C.TX1-")
			(pinfunction "A0TX+")
			(pintype "input")
		)
		(pad "36" smd roundrect
			(at 1.687 -3 270)
			(size 0.875 0.25)
			(layers "F.Cu" "F.Paste" "F.Mask")
			(roundrect_rratio 0.25)
			(net 23 "+3V3")
			(pinfunction "VCC")
			(pintype "passive")
		)
		(pad "37" smd roundrect
			(at 1.687 -3.5 270)
			(size 0.875 0.25)
			(layers "F.Cu" "F.Paste" "F.Mask")
			(roundrect_rratio 0.25)
			(net 100 "/TX_FG0")
			(pinfunction "FG0")
			(pintype "passive")
		)
		(pad "38" smd roundrect
			(at 1.687 -4 270)
			(size 0.875 0.25)
			(layers "F.Cu" "F.Paste" "F.Mask")
			(roundrect_rratio 0.25)
			(net 101 "/TX_FG1")
			(pinfunction "FG1")
			(pintype "passive")
		)
		(pad "39" smd roundrect
			(at 0.75 -4.438 270)
			(size 0.25 0.875)
			(layers "F.Cu" "F.Paste" "F.Mask")
			(roundrect_rratio 0.25)
			(net 96 "/TX_EQ0")
			(pinfunction "EQ0")
			(pintype "passive")
		)
		(pad "40" smd roundrect
			(at 0.25 -4.438 270)
			(size 0.25 0.875)
			(layers "F.Cu" "F.Paste" "F.Mask")
			(roundrect_rratio 0.25)
			(net 98 "/TX_EQ1")
			(pinfunction "EQ1")
			(pintype "passive")
		)
		(pad "41" smd roundrect
			(at -0.25 -4.438 270)
			(size 0.25 0.875)
			(layers "F.Cu" "F.Paste" "F.Mask")
			(roundrect_rratio 0.25)
			(net 51 "GND")
			(pinfunction "AD2")
			(pintype "passive")
		)
		(pad "42" smd roundrect
			(at -0.75 -4.438 270)
			(size 0.25 0.875)
			(layers "F.Cu" "F.Paste" "F.Mask")
			(roundrect_rratio 0.25)
			(net 51 "GND")
			(pinfunction "AD3")
			(pintype "passive")
		)
		(pad "43" smd rect
			(at 0 0 270)
			(size 2.05 7.55)
			(layers "F.Cu" "F.Mask")
			(net 51 "GND")
			(pinfunction "GND")
			(pintype "power_in")
		)
	)
)
